# T6G (Grand Teton) — schematic netlist excerpt (pin names and nets, part order shuffled) for the footprints in the layout excerpt that follows; sources: Cadence DE-HDL packaged netlist, KiCad conversion of 04192023_DAF0TMB3IC0_F0TG_MB_C_brd_V02_OCP.brd

R58  Q_RES  33 5% CHIP  pkg 0402LF  page 80 : A = SGPIO_SCM_INTR_R_N ; B = SGPIO_SCM_INTR_N
C2510  Q_CAP  22UF 4V 20% X6S  pkg C0402  page 74 : A = PVDD11_S3_P1 ; B = GND

(kicad_pcb
	(version 20260206)
	(generator "pcbnew")
	(generator_version "10.0")
	(general
		(thickness 1.6)
		(legacy_teardrops no)
	)
	(paper "A4")
	(title_block
		(title "04192023_DAF0TMB3IC0_F0TG_MB_C_brd_V02_OCP.brd")
		(comment 1 "Grand Teton / footprints 7313-7314 of 8354")
	)
	(layers
		(0 "F.Cu" signal "TOP")
		(4 "In1.Cu" signal "GND")
		(6 "In2.Cu" signal "IN1")
		(8 "In3.Cu" signal "GND1")
		(10 "In4.Cu" signal "IN2")
		(12 "In5.Cu" signal "GND2")
		(14 "In6.Cu" signal "IN3")
		(16 "In7.Cu" signal "GND3")
		(18 "In8.Cu" signal "VCC")
		(20 "In9.Cu" signal "VCC1")
		(22 "In10.Cu" signal "GND4")
		(24 "In11.Cu" signal "IN4")
		(26 "In12.Cu" signal "GND5")
		(28 "In13.Cu" signal "IN5")
		(30 "In14.Cu" signal "GND6")
		(32 "In15.Cu" signal "IN6")
		(34 "In16.Cu" signal "GND7")
		(2 "B.Cu" signal "BOTTOM")
		(9 "F.Adhes" user "F.Adhesive")
		(11 "B.Adhes" user "B.Adhesive")
		(13 "F.Paste" user "Package Geometry/Pastemask Top")
		(15 "B.Paste" user "Package Geometry/Pastemask Bottom")
		(5 "F.SilkS" user "Ref Des/Silkscreen Top")
		(7 "B.SilkS" user "Ref Des/Silkscreen Bottom")
		(1 "F.Mask" user "Board Geometry/Soldermask Top")
		(3 "B.Mask" user "Board Geometry/Soldermask Bottom")
		(17 "Dwgs.User" user "User.Drawings")
		(19 "Cmts.User" user "User.Comments")
		(21 "Eco1.User" user "User.Eco1")
		(23 "Eco2.User" user "User.Eco2")
		(25 "Edge.Cuts" user "Board Geometry/Outline")
		(27 "Margin" user)
		(31 "F.CrtYd" user "Package Geometry/Place Bound Top")
		(29 "B.CrtYd" user "Package Geometry/Place Bound Bottom")
		(35 "F.Fab" user "Ref Des/Assembly Top")
		(33 "B.Fab" user "Ref Des/Assembly Bottom")
	)
	(footprint ""
		(layer "B.Cu")
		(at 112.427004 -261.748016 90)
		(property "Reference" "C2510"
			(at 0 0 90)
			(layer "B.SilkS")
			(hide yes)
			(effects
				(font
					(size 1.27 1.27)
				)
				(justify mirror)
			)
		)
		(property "Value" ""
			(at 0 0 90)
			(layer "B.Fab")
			(effects
				(font
					(size 1.27 1.27)
				)
				(justify mirror)
			)
		)
		(duplicate_pad_numbers_are_jumpers no)
		(fp_line
			(start 0.7874 -0.4064)
			(end -0.7874 -0.4064)
			(stroke
				(width 0.1524)
				(type default)
			)
			(layer "B.SilkS")
		)
		(fp_line
			(start -0.7874 -0.4064)
			(end -0.7874 0.4064)
			(stroke
				(width 0.1524)
				(type default)
			)
			(layer "B.SilkS")
		)
		(fp_line
			(start 0.7874 0.4064)
			(end 0.7874 -0.4064)
			(stroke
				(width 0.1524)
				(type default)
			)
			(layer "B.SilkS")
		)
		(fp_line
			(start -0.7874 0.4064)
			(end 0.7874 0.4064)
			(stroke
				(width 0.1524)
				(type default)
			)
			(layer "B.SilkS")
		)
		(fp_line
			(start 0.67945 -0.305054)
			(end 0.12065 -0.305054)
			(stroke
				(width 0.1)
				(type default)
			)
			(layer "B.Fab")
		)
		(fp_line
			(start 0.12065 -0.305054)
			(end 0.12065 -0.2794)
			(stroke
				(width 0.1)
				(type default)
			)
			(layer "B.Fab")
		)
		(fp_line
			(start -0.12065 -0.3048)
			(end -0.67945 -0.3048)
			(stroke
				(width 0.1)
				(type default)
			)
			(layer "B.Fab")
		)
		(fp_line
			(start -0.67945 -0.3048)
			(end -0.67945 0.3048)
			(stroke
				(width 0.1)
				(type default)
			)
			(layer "B.Fab")
		)
		(fp_line
			(start 0.12065 -0.2794)
			(end -0.12065 -0.2794)
			(stroke
				(width 0.1)
				(type default)
			)
			(layer "B.Fab")
		)
		(fp_line
			(start -0.12065 -0.2794)
			(end -0.12065 -0.3048)
			(stroke
				(width 0.1)
				(type default)
			)
			(layer "B.Fab")
		)
		(fp_line
			(start 0.12065 0.2794)
			(end 0.12065 0.3048)
			(stroke
				(width 0.1)
				(type default)
			)
			(layer "B.Fab")
		)
		(fp_line
			(start -0.120396 0.2794)
			(end 0.12065 0.2794)
			(stroke
				(width 0.1)
				(type default)
			)
			(layer "B.Fab")
		)
		(fp_line
			(start 0.67945 0.3048)
			(end 0.67945 -0.305054)
			(stroke
				(width 0.1)
				(type default)
			)
			(layer "B.Fab")
		)
		(fp_line
			(start 0.12065 0.3048)
			(end 0.67945 0.3048)
			(stroke
				(width 0.1)
				(type default)
			)
			(layer "B.Fab")
		)
		(fp_line
			(start -0.120396 0.3048)
			(end -0.120396 0.2794)
			(stroke
				(width 0.1)
				(type default)
			)
			(layer "B.Fab")
		)
		(fp_line
			(start -0.67945 0.3048)
			(end -0.120396 0.3048)
			(stroke
				(width 0.1)
				(type default)
			)
			(layer "B.Fab")
		)
		(pad "1" smd circle
			(at 0.40005 0 270)
			(size 0 0)
			(layers "B.Cu" "B.Mask" "B.Paste")
			(net "PVDD11_S3_P1")
		)
		(pad "2" smd circle
			(at -0.40005 0 270)
			(size 0 0)
			(layers "B.Cu" "B.Mask" "B.Paste")
			(net "GND")
		)
	)
	(footprint ""
		(layer "B.Cu")
		(at 171.2341 -113.589308)
		(property "Reference" "R58"
			(at 0 0 0)
			(layer "B.SilkS")
			(hide yes)
			(effects
				(font
					(size 1.27 1.27)
				)
				(justify mirror)
			)
		)
		(property "Value" ""
			(at 0 0 0)
			(layer "B.Fab")
			(effects
				(font
					(size 1.27 1.27)
				)
				(justify mirror)
			)
		)
		(duplicate_pad_numbers_are_jumpers no)
		(fp_line
			(start -0.7874 -0.4064)
			(end -0.7874 0.4064)
			(stroke
				(width 0.1524)
				(type default)
			)
			(layer "B.SilkS")
		)
		(fp_line
			(start -0.7874 0.4064)
			(end 0.7874 0.4064)
			(stroke
				(width 0.1524)
				(type default)
			)
			(layer "B.SilkS")
		)
		(fp_line
			(start 0.7874 -0.4064)
			(end -0.7874 -0.4064)
			(stroke
				(width 0.1524)
				(type default)
			)
			(layer "B.SilkS")
		)
		(fp_line
			(start 0.7874 0.4064)
			(end 0.7874 -0.4064)
			(stroke
				(width 0.1524)
				(type default)
			)
			(layer "B.SilkS")
		)
		(fp_line
			(start -0.67945 -0.3048)
			(end -0.67945 0.3048)
			(stroke
				(width 0.1)
				(type default)
			)
			(layer "B.Fab")
		)
		(fp_line
			(start -0.67945 0.3048)
			(end -0.120396 0.3048)
			(stroke
				(width 0.1)
				(type default)
			)
			(layer "B.Fab")
		)
		(fp_line
			(start -0.12065 -0.3048)
			(end -0.67945 -0.3048)
			(stroke
				(width 0.1)
				(type default)
			)
			(layer "B.Fab")
		)
		(fp_line
			(start -0.12065 -0.2794)
			(end -0.12065 -0.3048)
			(stroke
				(width 0.1)
				(type default)
			)
			(layer "B.Fab")
		)
		(fp_line
			(start -0.120396 0.2794)
			(end 0.12065 0.2794)
			(stroke
				(width 0.1)
				(type default)
			)
			(layer "B.Fab")
		)
		(fp_line
			(start -0.120396 0.3048)
			(end -0.120396 0.2794)
			(stroke
				(width 0.1)
				(type default)
			)
			(layer "B.Fab")
		)
		(fp_line
			(start 0.12065 -0.305054)
			(end 0.12065 -0.2794)
			(stroke
				(width 0.1)
				(type default)
			)
			(layer "B.Fab")
		)
		(fp_line
			(start 0.12065 -0.2794)
			(end -0.12065 -0.2794)
			(stroke
				(width 0.1)
				(type default)
			)
			(layer "B.Fab")
		)
		(fp_line
			(start 0.12065 0.2794)
			(end 0.12065 0.3048)
			(stroke
				(width 0.1)
				(type default)
			)
			(layer "B.Fab")
		)
		(fp_line
			(start 0.12065 0.3048)
			(end 0.67945 0.3048)
			(stroke
				(width 0.1)
				(type default)
			)
			(layer "B.Fab")
		)
		(fp_line
			(start 0.67945 -0.305054)
			(end 0.12065 -0.305054)
			(stroke
				(width 0.1)
				(type default)
			)
			(layer "B.Fab")
		)
		(fp_line
			(start 0.67945 0.3048)
			(end 0.67945 -0.305054)
			(stroke
				(width 0.1)
				(type default)
			)
			(layer "B.Fab")
		)
		(pad "1" smd circle
			(at 0.40005 0 180)
			(size 0 0)
			(layers "B.Cu" "B.Mask" "B.Paste")
			(net "SGPIO_SCM_INTR_R_N")
		)
		(pad "2" smd circle
			(at -0.40005 0 180)
			(size 0 0)
			(layers "B.Cu" "B.Mask" "B.Paste")
			(net "SGPIO_SCM_INTR_N")
		)
	)
)
